# BASEBOARD_FAB2 (Tioga Pass) — schematic netlist excerpt (pin names and nets, part order shuffled) for the footprints in the layout excerpt that follows; sources: Cadence DE-HDL packaged netlist, KiCad conversion of Wiwynn_Tioga_Pass_MB.brd

R7P14  RES  240 1.0% CHIP  pkg 0402  page 90 : A = GND ; B = PD_CPU1_DMIMODE_OVERRIDE
C1R7  CAP  0.22UF 16V 10% X7R  pkg 0402  page 106 : A = P3E_CPU0_PE3_OCP_TXN<3> ; B = P3E_OCP_CPU0_PE3_C_TXN<3>
SH7U2  SHUNT  EMPTY  pkg SH0201  page 225 : A = VSENSE_PVDDQ_GHJ_N ; B = GND

(kicad_pcb
	(version 20260206)
	(generator "pcbnew")
	(generator_version "10.0")
	(general
		(thickness 1.6)
		(legacy_teardrops no)
	)
	(paper "A4")
	(title_block
		(title "Wiwynn_Tioga_Pass_MB.brd")
		(comment 1 "Tioga Pass / footprints 2631-2633 of 4770")
	)
	(layers
		(0 "F.Cu" signal "TOP")
		(4 "In1.Cu" signal "L2GND")
		(6 "In2.Cu" signal "L3")
		(8 "In3.Cu" signal "L4GND")
		(10 "In4.Cu" signal "L5")
		(12 "In5.Cu" signal "L6GND")
		(14 "In6.Cu" signal "L7VCC")
		(16 "In7.Cu" signal "L8VCC")
		(18 "In8.Cu" signal "L9GND")
		(20 "In9.Cu" signal "L10")
		(22 "In10.Cu" signal "L11GND")
		(24 "In11.Cu" signal "L12")
		(26 "In12.Cu" signal "L13GND")
		(2 "B.Cu" signal "BOTTOM")
		(9 "F.Adhes" user "F.Adhesive")
		(11 "B.Adhes" user "B.Adhesive")
		(13 "F.Paste" user "Package Geometry/Pastemask Top")
		(15 "B.Paste" user "Package Geometry/Pastemask Bottom")
		(5 "F.SilkS" user "Ref Des/Silkscreen Top")
		(7 "B.SilkS" user "Ref Des/Silkscreen Bottom")
		(1 "F.Mask" user "Board Geometry/Soldermask Top")
		(3 "B.Mask" user "Board Geometry/Soldermask Bottom")
		(17 "Dwgs.User" user "User.Drawings")
		(19 "Cmts.User" user "User.Comments")
		(21 "Eco1.User" user "User.Eco1")
		(23 "Eco2.User" user "User.Eco2")
		(25 "Edge.Cuts" user "Board Geometry/Outline")
		(27 "Margin" user)
		(31 "F.CrtYd" user "Package Geometry/Place Bound Top")
		(29 "B.CrtYd" user "Package Geometry/Place Bound Bottom")
		(35 "F.Fab" user "Ref Des/Assembly Top")
		(33 "B.Fab" user "Ref Des/Assembly Bottom")
	)
	(footprint ""
		(layer "B.Cu")
		(at 454.2282 -52.330858)
		(property "Reference" "C1R7"
			(at 0 0 0)
			(layer "B.SilkS")
			(hide yes)
			(effects
				(font
					(size 1.27 1.27)
				)
				(justify mirror)
			)
		)
		(property "Value" ""
			(at 0 0 0)
			(layer "B.Fab")
			(effects
				(font
					(size 1.27 1.27)
				)
				(justify mirror)
			)
		)
		(duplicate_pad_numbers_are_jumpers no)
		(fp_poly
			(pts
				(xy -0.3048 -0.1016) (xy -0.3048 0.9906) (xy 0.3048 0.9906) (xy 0.3048 -0.1016)
			)
			(stroke
				(width 0)
				(type default)
			)
			(fill no)
			(layer "B.CrtYd")
		)
		(fp_line
			(start -0.3048 -0.1016)
			(end 0.3048 -0.1016)
			(stroke
				(width 0.1)
				(type default)
			)
			(layer "B.Fab")
		)
		(fp_line
			(start -0.3048 0.9906)
			(end -0.3048 -0.1016)
			(stroke
				(width 0.1)
				(type default)
			)
			(layer "B.Fab")
		)
		(fp_line
			(start 0.3048 -0.1016)
			(end 0.3048 0.9906)
			(stroke
				(width 0.1)
				(type default)
			)
			(layer "B.Fab")
		)
		(fp_line
			(start 0.3048 0.9906)
			(end -0.3048 0.9906)
			(stroke
				(width 0.1)
				(type default)
			)
			(layer "B.Fab")
		)
		(pad "1" smd rect
			(at 0 0 180)
			(size 0.508 0.508)
			(layers "B.Cu" "B.Mask" "B.Paste")
			(net "P3E_CPU0_PE3_OCP_TXN<3>")
		)
		(pad "2" smd rect
			(at 0 0.889 180)
			(size 0.508 0.508)
			(layers "B.Cu" "B.Mask" "B.Paste")
			(net "P3E_OCP_CPU0_PE3_C_TXN<3>")
		)
		(zone
			(layer "B.Cu")
			(hatch none 0.5)
			(connect_pads
				(clearance 0)
			)
			(min_thickness 0.25)
			(keepout
				(tracks allowed)
				(vias not_allowed)
				(pads allowed)
				(copperpour not_allowed)
				(footprints allowed)
			)
			(placement
				(enabled no)
				(sheetname "")
			)
			(fill
				(thermal_gap 0.5)
				(thermal_bridge_width 0.5)
				(island_removal_mode 0)
			)
			(polygon
				(pts
					(xy 454.4822 -52.076858) (xy 453.9742 -52.076858) (xy 453.9742 -51.695858) (xy 454.4822 -51.695858)
				)
			)
		)
	)
	(footprint ""
		(layer "B.Cu")
		(at 113.761012 -29.94152 90)
		(property "Reference" "SH7U2"
			(at 0 0 90)
			(layer "B.SilkS")
			(hide yes)
			(effects
				(font
					(size 1.27 1.27)
				)
				(justify mirror)
			)
		)
		(property "Value" ""
			(at 0 0 90)
			(layer "B.Fab")
			(effects
				(font
					(size 1.27 1.27)
				)
				(justify mirror)
			)
		)
		(duplicate_pad_numbers_are_jumpers no)
		(fp_poly
			(pts
				(xy 0.1651 -0.0508) (xy 0.1651 0.5842) (xy -0.1651 0.5842) (xy -0.1651 -0.0508)
			)
			(stroke
				(width 0)
				(type default)
			)
			(fill no)
			(layer "B.CrtYd")
		)
		(fp_line
			(start 0.1651 -0.0508)
			(end -0.1651 -0.0508)
			(stroke
				(width 0.1)
				(type default)
			)
			(layer "B.Fab")
		)
		(fp_line
			(start -0.1651 -0.0508)
			(end -0.1651 0.5842)
			(stroke
				(width 0.1)
				(type default)
			)
			(layer "B.Fab")
		)
		(fp_line
			(start 0.1651 0.5842)
			(end 0.1651 -0.0508)
			(stroke
				(width 0.1)
				(type default)
			)
			(layer "B.Fab")
		)
		(fp_line
			(start -0.1651 0.5842)
			(end 0.1651 0.5842)
			(stroke
				(width 0.1)
				(type default)
			)
			(layer "B.Fab")
		)
		(pad "1" smd custom
			(at 0 0 90)
			(size 0.0762 0.0762)
			(layers "B.Cu" "B.Mask" "B.Paste")
			(net "VSENSE_PVDDQ_GHJ_N")
			(options
				(clearance outline)
				(anchor circle)
			)
			(primitives
				(gr_poly
					(pts
						(arc
							(start -0.1524 0.10795)
							(mid -0.098518 0.130268)
							(end -0.0762 0.18415)
						)
						(xy -0.0762 0.22225) (xy 0.0762 0.22225)
						(arc
							(start 0.0762 0.18415)
							(mid 0.098518 0.130268)
							(end 0.1524 0.10795)
						)
						(xy 0.1524 -0.22225) (xy -0.1524 -0.22225)
					)
					(width 0)
					(fill yes)
				)
			)
		)
		(pad "2" smd custom
			(at 0 0.5334 270)
			(size 0.0762 0.0762)
			(layers "B.Cu" "B.Mask" "B.Paste")
			(net "GND")
			(options
				(clearance outline)
				(anchor circle)
			)
			(primitives
				(gr_poly
					(pts
						(arc
							(start -0.1524 0.10795)
							(mid -0.098518 0.130268)
							(end -0.0762 0.18415)
						)
						(xy -0.0762 0.22225) (xy 0.0762 0.22225)
						(arc
							(start 0.0762 0.18415)
							(mid 0.098518 0.130268)
							(end 0.1524 0.10795)
						)
						(xy 0.1524 -0.22225) (xy -0.1524 -0.22225)
					)
					(width 0)
					(fill yes)
				)
			)
		)
	)
	(footprint ""
		(layer "B.Cu")
		(at 116.332 -75.692 90)
		(property "Reference" "R7P14"
			(at 0 0 90)
			(layer "B.SilkS")
			(hide yes)
			(effects
				(font
					(size 1.27 1.27)
				)
				(justify mirror)
			)
		)
		(property "Value" ""
			(at 0 0 90)
			(layer "B.Fab")
			(effects
				(font
					(size 1.27 1.27)
				)
				(justify mirror)
			)
		)
		(duplicate_pad_numbers_are_jumpers no)
		(fp_poly
			(pts
				(xy 0.2794 -0.1016) (xy -0.2794 -0.1016) (xy -0.2794 0.9906) (xy 0.2794 0.9906)
			)
			(stroke
				(width 0)
				(type default)
			)
			(fill no)
			(layer "B.CrtYd")
		)
		(fp_line
			(start 0.2794 -0.1016)
			(end 0.2794 0.9906)
			(stroke
				(width 0.1)
				(type default)
			)
			(layer "B.Fab")
		)
		(fp_line
			(start -0.2794 -0.1016)
			(end 0.2794 -0.1016)
			(stroke
				(width 0.1)
				(type default)
			)
			(layer "B.Fab")
		)
		(fp_line
			(start 0.2794 0.9906)
			(end -0.2794 0.9906)
			(stroke
				(width 0.1)
				(type default)
			)
			(layer "B.Fab")
		)
		(fp_line
			(start -0.2794 0.9906)
			(end -0.2794 -0.1016)
			(stroke
				(width 0.1)
				(type default)
			)
			(layer "B.Fab")
		)
		(pad "1" smd rect
			(at 0 0 270)
			(size 0.508 0.508)
			(layers "B.Cu" "B.Mask" "B.Paste")
			(net "GND")
		)
		(pad "2" smd rect
			(at 0 0.889 270)
			(size 0.508 0.508)
			(layers "B.Cu" "B.Mask" "B.Paste")
			(net "PD_CPU1_DMIMODE_OVERRIDE")
		)
		(zone
			(layer "B.Cu")
			(hatch none 0.5)
			(connect_pads
				(clearance 0)
			)
			(min_thickness 0.25)
			(keepout
				(tracks allowed)
				(vias not_allowed)
				(pads allowed)
				(copperpour not_allowed)
				(footprints allowed)
			)
			(placement
				(enabled no)
				(sheetname "")
			)
			(fill
				(thermal_gap 0.5)
				(thermal_bridge_width 0.5)
				(island_removal_mode 0)
			)
			(polygon
				(pts
					(xy 116.586 -75.946) (xy 116.586 -75.438) (xy 116.967 -75.438) (xy 116.967 -75.946)
				)
			)
		)
		(zone
			(layer "B.Cu")
			(hatch none 0.5)
			(connect_pads
				(clearance 0)
			)
			(min_thickness 0.25)
			(keepout
				(tracks not_allowed)
				(vias allowed)
				(pads allowed)
				(copperpour not_allowed)
				(footprints allowed)
			)
			(placement
				(enabled no)
				(sheetname "")
			)
			(fill
				(thermal_gap 0.5)
				(thermal_bridge_width 0.5)
				(island_removal_mode 0)
			)
			(polygon
				(pts
					(xy 116.967 -75.946) (xy 116.967 -75.438) (xy 116.586 -75.438) (xy 116.586 -75.946)
				)
			)
		)
	)
)
